(kicad_pcb
	(version 20260206)
	(generator "pcbnew")
	(generator_version "10.0")
	(general
		(thickness 1.6)
		(legacy_teardrops no)
	)
	(paper "A4")
	(title_block
		(title "Bryce Canyon_IOM_IOC_16318-2_OCP.brd")
		(comment 1 "Bryce Canyon / footprints 1139-1146 of 1605")
	)
	(layers
		(0 "F.Cu" signal "TOP")
		(4 "In1.Cu" signal "L2GND")
		(6 "In2.Cu" signal "L3")
		(8 "In3.Cu" signal "L4VCC")
		(10 "In4.Cu" signal "L5VCC")
		(12 "In5.Cu" signal "L6")
		(14 "In6.Cu" signal "L7GND")
		(2 "B.Cu" signal "BOTTOM")
		(9 "F.Adhes" user "F.Adhesive")
		(11 "B.Adhes" user "B.Adhesive")
		(13 "F.Paste" user "Package Geometry/Pastemask Top")
		(15 "B.Paste" user "Package Geometry/Pastemask Bottom")
		(5 "F.SilkS" user "Ref Des/Silkscreen Top")
		(7 "B.SilkS" user "Ref Des/Silkscreen Bottom")
		(1 "F.Mask" user "Board Geometry/Soldermask Top")
		(3 "B.Mask" user "Board Geometry/Soldermask Bottom")
		(17 "Dwgs.User" user "User.Drawings")
		(19 "Cmts.User" user "User.Comments")
		(21 "Eco1.User" user "User.Eco1")
		(23 "Eco2.User" user "User.Eco2")
		(25 "Edge.Cuts" user "Board Geometry/Outline")
		(27 "Margin" user)
		(31 "F.CrtYd" user "Package Geometry/Place Bound Top")
		(29 "B.CrtYd" user "Package Geometry/Place Bound Bottom")
		(35 "F.Fab" user "Ref Des/Assembly Top")
		(33 "B.Fab" user "Ref Des/Assembly Bottom")
	)
	(footprint ""
		(layer "B.Cu")
		(at 205.568804 -92.825824 180)
		(property "Reference" "L19"
			(at 0 0 0)
			(layer "B.SilkS")
			(hide yes)
			(effects
				(font
					(size 1.27 1.27)
				)
				(justify mirror)
			)
		)
		(property "Value" "MPZ2012S601AT-GP"
			(at 0 -4.2418 180)
			(unlocked yes)
			(layer "B.Fab")
			(hide yes)
			(effects
				(font
					(size 1.016 1.016)
					(thickness 0.1524)
				)
				(justify mirror)
			)
		)
		(property "Device Type" "L805H42"
			(at 0 -5.7912 180)
			(unlocked yes)
			(layer "B.Fab")
			(hide yes)
			(effects
				(font
					(size 1.016 1.016)
					(thickness 0.1524)
				)
				(justify mirror)
			)
		)
		(duplicate_pad_numbers_are_jumpers no)
		(fp_line
			(start 0.889 1.7018)
			(end 0.889 -1.7018)
			(stroke
				(width 0.1524)
				(type default)
			)
			(layer "B.SilkS")
		)
		(fp_line
			(start 0.889 -1.7018)
			(end -0.889 -1.7018)
			(stroke
				(width 0.1524)
				(type default)
			)
			(layer "B.SilkS")
		)
		(fp_line
			(start -0.889 1.7018)
			(end 0.889 1.7018)
			(stroke
				(width 0.1524)
				(type default)
			)
			(layer "B.SilkS")
		)
		(fp_line
			(start -0.889 -1.7018)
			(end -0.889 1.7018)
			(stroke
				(width 0.1524)
				(type default)
			)
			(layer "B.SilkS")
		)
		(fp_rect
			(start 0.9652 1.778)
			(end -0.9652 -1.778)
			(stroke
				(width 0)
				(type default)
			)
			(fill no)
			(layer "B.CrtYd")
		)
		(fp_rect
			(start 0.9652 1.778)
			(end -0.9652 -1.778)
			(stroke
				(width 0)
				(type default)
			)
			(fill no)
			(layer "B.Fab")
		)
		(pad "1" smd rect
			(at 0 -0.9652)
			(size 1.397 1.143)
			(layers "B.Cu" "B.Mask" "B.Paste")
			(net "PCE_VDDH")
		)
		(pad "2" smd rect
			(at 0 0.9652)
			(size 1.397 1.143)
			(layers "B.Cu" "B.Mask" "B.Paste")
			(net "P1V5")
		)
	)
	(footprint ""
		(layer "B.Cu")
		(at 186.8424 -124.405136 180)
		(property "Reference" "R560"
			(at 0 0 0)
			(layer "B.SilkS")
			(hide yes)
			(effects
				(font
					(size 1.27 1.27)
				)
				(justify mirror)
			)
		)
		(property "Value" "69K8R2F-GP"
			(at -0.064008 -3.993896 180)
			(unlocked yes)
			(layer "B.Fab")
			(hide yes)
			(effects
				(font
					(size 1.016 1.016)
					(thickness 0.1524)
				)
				(justify mirror)
			)
		)
		(property "Device Type" "R402H16"
			(at -0.064008 -5.517896 180)
			(unlocked yes)
			(layer "B.Fab")
			(hide yes)
			(effects
				(font
					(size 1.016 1.016)
					(thickness 0.1524)
				)
				(justify mirror)
			)
		)
		(duplicate_pad_numbers_are_jumpers no)
		(fp_line
			(start 0.508 -0.9398)
			(end 0.508 0.9398)
			(stroke
				(width 0.1524)
				(type default)
			)
			(layer "B.SilkS")
		)
		(fp_line
			(start -0.508 -0.9398)
			(end 0.508 -0.9398)
			(stroke
				(width 0.1524)
				(type default)
			)
			(layer "B.SilkS")
		)
		(fp_rect
			(start 0.508 0.9398)
			(end -0.508 -0.9398)
			(stroke
				(width 0)
				(type default)
			)
			(fill no)
			(layer "B.CrtYd")
		)
		(fp_rect
			(start 0.508 0.9398)
			(end -0.508 -0.9398)
			(stroke
				(width 0)
				(type default)
			)
			(fill no)
			(layer "B.Fab")
		)
		(pad "1" smd custom
			(at 0 -0.4445)
			(size 0.1397 0.1397)
			(layers "B.Cu" "B.Mask" "B.Paste")
			(net "AGND_P0V975")
			(options
				(clearance outline)
				(anchor circle)
			)
			(primitives
				(gr_poly
					(pts
						(arc
							(start -0.1778 0.2794)
							(mid -0.249642 0.249642)
							(end -0.2794 0.1778)
						)
						(arc
							(start -0.2794 -0.1778)
							(mid -0.249642 -0.249642)
							(end -0.1778 -0.2794)
						)
						(arc
							(start 0.1778 -0.2794)
							(mid 0.249642 -0.249642)
							(end 0.2794 -0.1778)
						)
						(arc
							(start 0.2794 0.1778)
							(mid 0.249642 0.249642)
							(end 0.1778 0.2794)
						)
					)
					(width 0)
					(fill yes)
				)
			)
		)
		(pad "2" smd custom
			(at 0 0.4445)
			(size 0.1397 0.1397)
			(layers "B.Cu" "B.Mask" "B.Paste")
			(net "VT235_IRIP")
			(options
				(clearance outline)
				(anchor circle)
			)
			(primitives
				(gr_poly
					(pts
						(arc
							(start -0.1778 0.2794)
							(mid -0.249642 0.249642)
							(end -0.2794 0.1778)
						)
						(arc
							(start -0.2794 -0.1778)
							(mid -0.249642 -0.249642)
							(end -0.1778 -0.2794)
						)
						(arc
							(start 0.1778 -0.2794)
							(mid 0.249642 -0.249642)
							(end 0.2794 -0.1778)
						)
						(arc
							(start 0.2794 0.1778)
							(mid 0.249642 0.249642)
							(end 0.1778 0.2794)
						)
					)
					(width 0)
					(fill yes)
				)
			)
		)
	)
	(footprint ""
		(layer "B.Cu")
		(at 189.640718 -81.153 180)
		(property "Reference" "C302"
			(at 0 0 0)
			(layer "B.SilkS")
			(hide yes)
			(effects
				(font
					(size 1.27 1.27)
				)
				(justify mirror)
			)
		)
		(property "Value" "SCD22U10V1KX-GP"
			(at 2.8321 -1.7399 180)
			(unlocked yes)
			(layer "B.Fab")
			(hide yes)
			(effects
				(font
					(size 1.016 1.016)
					(thickness 0.1524)
				)
				(justify mirror)
			)
		)
		(property "Device Type" "C0201H13"
			(at 2.8321 -3.2639 180)
			(unlocked yes)
			(layer "B.Fab")
			(hide yes)
			(effects
				(font
					(size 1.016 1.016)
					(thickness 0.1524)
				)
				(justify mirror)
			)
		)
		(duplicate_pad_numbers_are_jumpers no)
		(fp_rect
			(start 0.2794 0.6477)
			(end -0.2794 -0.6477)
			(stroke
				(width 0)
				(type default)
			)
			(fill no)
			(layer "B.CrtYd")
		)
		(fp_rect
			(start 0.2794 0.6477)
			(end -0.2794 -0.6477)
			(stroke
				(width 0)
				(type default)
			)
			(fill no)
			(layer "B.Fab")
		)
		(pad "1" smd custom
			(at 0 -0.2794)
			(size 0.0762 0.0762)
			(layers "B.Cu" "B.Mask" "B.Paste")
			(net "PCIE_IOM_TO_COMP_14_DN_C")
			(options
				(clearance outline)
				(anchor circle)
			)
			(primitives
				(gr_poly
					(pts
						(arc
							(start 0.1524 0.127)
							(mid 0.137521 0.162921)
							(end 0.1016 0.1778)
						)
						(arc
							(start -0.1016 0.1778)
							(mid -0.137521 0.162921)
							(end -0.1524 0.127)
						)
						(arc
							(start -0.1524 -0.127)
							(mid -0.137521 -0.162921)
							(end -0.1016 -0.1778)
						)
						(arc
							(start 0.1016 -0.1778)
							(mid 0.137521 -0.162921)
							(end 0.1524 -0.127)
						)
					)
					(width 0)
					(fill yes)
				)
			)
		)
		(pad "2" smd custom
			(at 0 0.2794)
			(size 0.0762 0.0762)
			(layers "B.Cu" "B.Mask" "B.Paste")
			(net "PCIE_IOM_TO_COMP_14_DN")
			(options
				(clearance outline)
				(anchor circle)
			)
			(primitives
				(gr_poly
					(pts
						(arc
							(start 0.1524 0.127)
							(mid 0.137521 0.162921)
							(end 0.1016 0.1778)
						)
						(arc
							(start -0.1016 0.1778)
							(mid -0.137521 0.162921)
							(end -0.1524 0.127)
						)
						(arc
							(start -0.1524 -0.127)
							(mid -0.137521 -0.162921)
							(end -0.1016 -0.1778)
						)
						(arc
							(start 0.1016 -0.1778)
							(mid 0.137521 -0.162921)
							(end 0.1524 -0.127)
						)
					)
					(width 0)
					(fill yes)
				)
			)
		)
	)
	(footprint ""
		(layer "B.Cu")
		(at 31.1404 -150.7744)
		(property "Reference" "L3"
			(at 0 0 0)
			(layer "B.SilkS")
			(hide yes)
			(effects
				(font
					(size 1.27 1.27)
				)
				(justify mirror)
			)
		)
		(property "Value" "MMZ2012S601ATA1N-GP"
			(at 0 -4.2418 0)
			(unlocked yes)
			(layer "B.Fab")
			(hide yes)
			(effects
				(font
					(size 1.016 1.016)
					(thickness 0.1524)
				)
				(justify mirror)
			)
		)
		(property "Device Type" "L805H42"
			(at 0 -5.7912 0)
			(unlocked yes)
			(layer "B.Fab")
			(hide yes)
			(effects
				(font
					(size 1.016 1.016)
					(thickness 0.1524)
				)
				(justify mirror)
			)
		)
		(duplicate_pad_numbers_are_jumpers no)
		(fp_line
			(start -0.889 -1.7018)
			(end -0.889 1.7018)
			(stroke
				(width 0.1524)
				(type default)
			)
			(layer "B.SilkS")
		)
		(fp_line
			(start -0.889 1.7018)
			(end 0.889 1.7018)
			(stroke
				(width 0.1524)
				(type default)
			)
			(layer "B.SilkS")
		)
		(fp_line
			(start 0.889 -1.7018)
			(end -0.889 -1.7018)
			(stroke
				(width 0.1524)
				(type default)
			)
			(layer "B.SilkS")
		)
		(fp_line
			(start 0.889 1.7018)
			(end 0.889 -1.7018)
			(stroke
				(width 0.1524)
				(type default)
			)
			(layer "B.SilkS")
		)
		(fp_rect
			(start 0.9652 1.778)
			(end -0.9652 -1.778)
			(stroke
				(width 0)
				(type default)
			)
			(fill no)
			(layer "B.CrtYd")
		)
		(fp_rect
			(start 0.9652 1.778)
			(end -0.9652 -1.778)
			(stroke
				(width 0)
				(type default)
			)
			(fill no)
			(layer "B.Fab")
		)
		(pad "1" smd rect
			(at 0 -0.9652 180)
			(size 1.397 1.143)
			(layers "B.Cu" "B.Mask" "B.Paste")
			(net "P3V3_STBY")
		)
		(pad "2" smd rect
			(at 0 0.9652 180)
			(size 1.397 1.143)
			(layers "B.Cu" "B.Mask" "B.Paste")
			(net "MPLLAV33")
		)
	)
	(footprint ""
		(layer "B.Cu")
		(at 192.405 -64.8208 90)
		(property "Reference" "C416"
			(at 0 0 90)
			(layer "B.SilkS")
			(hide yes)
			(effects
				(font
					(size 1.27 1.27)
				)
				(justify mirror)
			)
		)
		(property "Value" "SCD1U6D3V1KX-GP"
			(at 2.8321 -1.7399 90)
			(unlocked yes)
			(layer "B.Fab")
			(hide yes)
			(effects
				(font
					(size 1.016 1.016)
					(thickness 0.1524)
				)
				(justify mirror)
			)
		)
		(property "Device Type" "C0201H13"
			(at 2.8321 -3.2639 90)
			(unlocked yes)
			(layer "B.Fab")
			(hide yes)
			(effects
				(font
					(size 1.016 1.016)
					(thickness 0.1524)
				)
				(justify mirror)
			)
		)
		(duplicate_pad_numbers_are_jumpers no)
		(fp_rect
			(start 0.2794 0.6477)
			(end -0.2794 -0.6477)
			(stroke
				(width 0)
				(type default)
			)
			(fill no)
			(layer "B.CrtYd")
		)
		(fp_rect
			(start 0.2794 0.6477)
			(end -0.2794 -0.6477)
			(stroke
				(width 0)
				(type default)
			)
			(fill no)
			(layer "B.Fab")
		)
		(pad "1" smd custom
			(at 0 -0.2794 270)
			(size 0.0762 0.0762)
			(layers "B.Cu" "B.Mask" "B.Paste")
			(net "P0V975")
			(options
				(clearance outline)
				(anchor circle)
			)
			(primitives
				(gr_poly
					(pts
						(arc
							(start 0.1524 0.127)
							(mid 0.137521 0.162921)
							(end 0.1016 0.1778)
						)
						(arc
							(start -0.1016 0.1778)
							(mid -0.137521 0.162921)
							(end -0.1524 0.127)
						)
						(arc
							(start -0.1524 -0.127)
							(mid -0.137521 -0.162921)
							(end -0.1016 -0.1778)
						)
						(arc
							(start 0.1016 -0.1778)
							(mid 0.137521 -0.162921)
							(end 0.1524 -0.127)
						)
					)
					(width 0)
					(fill yes)
				)
			)
		)
		(pad "2" smd custom
			(at 0 0.2794 270)
			(size 0.0762 0.0762)
			(layers "B.Cu" "B.Mask" "B.Paste")
			(net "GND")
			(options
				(clearance outline)
				(anchor circle)
			)
			(primitives
				(gr_poly
					(pts
						(arc
							(start 0.1524 0.127)
							(mid 0.137521 0.162921)
							(end 0.1016 0.1778)
						)
						(arc
							(start -0.1016 0.1778)
							(mid -0.137521 0.162921)
							(end -0.1524 0.127)
						)
						(arc
							(start -0.1524 -0.127)
							(mid -0.137521 -0.162921)
							(end -0.1016 -0.1778)
						)
						(arc
							(start 0.1016 -0.1778)
							(mid 0.137521 -0.162921)
							(end 0.1524 -0.127)
						)
					)
					(width 0)
					(fill yes)
				)
			)
		)
	)
	(footprint ""
		(layer "B.Cu")
		(at 204.461872 -70.729856 -90)
		(property "Reference" "C353"
			(at 0 0 90)
			(layer "B.SilkS")
			(hide yes)
			(effects
				(font
					(size 1.27 1.27)
				)
				(justify mirror)
			)
		)
		(property "Value" "SCD1U6D3V1KX-GP"
			(at 2.8321 -1.7399 270)
			(unlocked yes)
			(layer "B.Fab")
			(hide yes)
			(effects
				(font
					(size 1.016 1.016)
					(thickness 0.1524)
				)
				(justify mirror)
			)
		)
		(property "Device Type" "C0201H13"
			(at 2.8321 -3.2639 270)
			(unlocked yes)
			(layer "B.Fab")
			(hide yes)
			(effects
				(font
					(size 1.016 1.016)
					(thickness 0.1524)
				)
				(justify mirror)
			)
		)
		(duplicate_pad_numbers_are_jumpers no)
		(fp_rect
			(start 0.2794 0.6477)
			(end -0.2794 -0.6477)
			(stroke
				(width 0)
				(type default)
			)
			(fill no)
			(layer "B.CrtYd")
		)
		(fp_rect
			(start 0.2794 0.6477)
			(end -0.2794 -0.6477)
			(stroke
				(width 0)
				(type default)
			)
			(fill no)
			(layer "B.Fab")
		)
		(pad "1" smd custom
			(at 0 -0.2794 90)
			(size 0.0762 0.0762)
			(layers "B.Cu" "B.Mask" "B.Paste")
			(net "SAS0_VDDH")
			(options
				(clearance outline)
				(anchor circle)
			)
			(primitives
				(gr_poly
					(pts
						(arc
							(start 0.1524 0.127)
							(mid 0.137521 0.162921)
							(end 0.1016 0.1778)
						)
						(arc
							(start -0.1016 0.1778)
							(mid -0.137521 0.162921)
							(end -0.1524 0.127)
						)
						(arc
							(start -0.1524 -0.127)
							(mid -0.137521 -0.162921)
							(end -0.1016 -0.1778)
						)
						(arc
							(start 0.1016 -0.1778)
							(mid 0.137521 -0.162921)
							(end 0.1524 -0.127)
						)
					)
					(width 0)
					(fill yes)
				)
			)
		)
		(pad "2" smd custom
			(at 0 0.2794 90)
			(size 0.0762 0.0762)
			(layers "B.Cu" "B.Mask" "B.Paste")
			(net "GND")
			(options
				(clearance outline)
				(anchor circle)
			)
			(primitives
				(gr_poly
					(pts
						(arc
							(start 0.1524 0.127)
							(mid 0.137521 0.162921)
							(end 0.1016 0.1778)
						)
						(arc
							(start -0.1016 0.1778)
							(mid -0.137521 0.162921)
							(end -0.1524 0.127)
						)
						(arc
							(start -0.1524 -0.127)
							(mid -0.137521 -0.162921)
							(end -0.1016 -0.1778)
						)
						(arc
							(start 0.1016 -0.1778)
							(mid 0.137521 -0.162921)
							(end 0.1524 -0.127)
						)
					)
					(width 0)
					(fill yes)
				)
			)
		)
	)
	(footprint ""
		(layer "B.Cu")
		(at 177.0888 -138.4554 180)
		(property "Reference" "R464"
			(at 0 0 0)
			(layer "B.SilkS")
			(hide yes)
			(effects
				(font
					(size 1.27 1.27)
				)
				(justify mirror)
			)
		)
		(property "Value" "2D2R3-1-U-GP"
			(at 0.0254 -2.5146 180)
			(unlocked yes)
			(layer "B.Fab")
			(hide yes)
			(effects
				(font
					(size 1.016 1.016)
					(thickness 0.1524)
				)
				(justify mirror)
			)
		)
		(property "Device Type" "R603H22"
			(at 0.0254 -4.0386 180)
			(unlocked yes)
			(layer "B.Fab")
			(hide yes)
			(effects
				(font
					(size 1.016 1.016)
					(thickness 0.1524)
				)
				(justify mirror)
			)
		)
		(duplicate_pad_numbers_are_jumpers no)
		(fp_line
			(start 0.4826 0)
			(end 0.2032 0)
			(stroke
				(width 0.2032)
				(type default)
			)
			(layer "B.SilkS")
		)
		(fp_line
			(start -0.2032 0)
			(end -0.4826 0)
			(stroke
				(width 0.2032)
				(type default)
			)
			(layer "B.SilkS")
		)
		(fp_rect
			(start 0.5842 1.3335)
			(end -0.5842 -1.3335)
			(stroke
				(width 0)
				(type default)
			)
			(fill no)
			(layer "B.CrtYd")
		)
		(fp_rect
			(start 0.5842 1.3335)
			(end -0.5842 -1.3335)
			(stroke
				(width 0)
				(type default)
			)
			(fill no)
			(layer "B.Fab")
		)
		(pad "1" smd custom
			(at 0 -0.762)
			(size 0.2159 0.2159)
			(layers "B.Cu" "B.Mask" "B.Paste")
			(net "P12V_STBY")
			(options
				(clearance outline)
				(anchor circle)
			)
			(primitives
				(gr_poly
					(pts
						(arc
							(start -0.3302 0.4318)
							(mid -0.402042 0.402042)
							(end -0.4318 0.3302)
						)
						(arc
							(start -0.4318 -0.3302)
							(mid -0.402042 -0.402042)
							(end -0.3302 -0.4318)
						)
						(arc
							(start 0.3302 -0.4318)
							(mid 0.402042 -0.402042)
							(end 0.4318 -0.3302)
						)
						(arc
							(start 0.4318 0.3302)
							(mid 0.402042 0.402042)
							(end 0.3302 0.4318)
						)
					)
					(width 0)
					(fill yes)
				)
			)
		)
		(pad "2" smd custom
			(at 0 0.762)
			(size 0.2159 0.2159)
			(layers "B.Cu" "B.Mask" "B.Paste")
			(net "P12V_STBY_VDD_PU1")
			(options
				(clearance outline)
				(anchor circle)
			)
			(primitives
				(gr_poly
					(pts
						(arc
							(start -0.3302 0.4318)
							(mid -0.402042 0.402042)
							(end -0.4318 0.3302)
						)
						(arc
							(start -0.4318 -0.3302)
							(mid -0.402042 -0.402042)
							(end -0.3302 -0.4318)
						)
						(arc
							(start 0.3302 -0.4318)
							(mid 0.402042 -0.402042)
							(end 0.4318 -0.3302)
						)
						(arc
							(start 0.4318 0.3302)
							(mid 0.402042 0.402042)
							(end 0.3302 0.4318)
						)
					)
					(width 0)
					(fill yes)
				)
			)
		)
	)
	(footprint ""
		(layer "B.Cu")
		(at 192.786 -54.0766)
		(property "Reference" "C460"
			(at 0 0 0)
			(layer "B.SilkS")
			(hide yes)
			(effects
				(font
					(size 1.27 1.27)
				)
				(justify mirror)
			)
		)
		(property "Value" "SCD1U16V2KX-3GP"
			(at -1.1811 -2.7051 0)
			(unlocked yes)
			(layer "B.Fab")
			(hide yes)
			(effects
				(font
					(size 1.016 1.016)
					(thickness 0.1524)
				)
				(justify mirror)
			)
		)
		(property "Device Type" "C402H22"
			(at -1.1811 -4.2291 0)
			(unlocked yes)
			(layer "B.Fab")
			(hide yes)
			(effects
				(font
					(size 1.016 1.016)
					(thickness 0.1524)
				)
				(justify mirror)
			)
		)
		(duplicate_pad_numbers_are_jumpers no)
		(fp_rect
			(start 0.4318 0.9525)
			(end -0.4318 -0.9525)
			(stroke
				(width 0)
				(type default)
			)
			(fill no)
			(layer "B.CrtYd")
		)
		(fp_rect
			(start 0.4318 0.9525)
			(end -0.4318 -0.9525)
			(stroke
				(width 0)
				(type default)
			)
			(fill no)
			(layer "B.Fab")
		)
		(pad "1" smd custom
			(at 0 -0.4445 180)
			(size 0.1524 0.1524)
			(layers "B.Cu" "B.Mask" "B.Paste")
			(net "P1V8")
			(options
				(clearance outline)
				(anchor circle)
			)
			(primitives
				(gr_poly
					(pts
						(arc
							(start 0.3048 0.2032)
							(mid 0.275042 0.275042)
							(end 0.2032 0.3048)
						)
						(arc
							(start -0.2032 0.3048)
							(mid -0.275042 0.275042)
							(end -0.3048 0.2032)
						)
						(arc
							(start -0.3048 -0.2032)
							(mid -0.275042 -0.275042)
							(end -0.2032 -0.3048)
						)
						(arc
							(start 0.2032 -0.3048)
							(mid 0.275042 -0.275042)
							(end 0.3048 -0.2032)
						)
					)
					(width 0)
					(fill yes)
				)
			)
		)
		(pad "2" smd custom
			(at 0 0.4445 180)
			(size 0.1524 0.1524)
			(layers "B.Cu" "B.Mask" "B.Paste")
			(net "GND")
			(options
				(clearance outline)
				(anchor circle)
			)
			(primitives
				(gr_poly
					(pts
						(arc
							(start 0.3048 0.2032)
							(mid 0.275042 0.275042)
							(end 0.2032 0.3048)
						)
						(arc
							(start -0.2032 0.3048)
							(mid -0.275042 0.275042)
							(end -0.3048 0.2032)
						)
						(arc
							(start -0.3048 -0.2032)
							(mid -0.275042 -0.275042)
							(end -0.2032 -0.3048)
						)
						(arc
							(start 0.2032 -0.3048)
							(mid 0.275042 -0.275042)
							(end 0.3048 -0.2032)
						)
					)
					(width 0)
					(fill yes)
				)
			)
		)
	)
)
